# BASEBOARD_FAB2 (Tioga Pass) — schematic netlist excerpt (pin names and nets, part order shuffled) for the footprints in the layout excerpt that follows; sources: Cadence DE-HDL packaged netlist, KiCad conversion of Wiwynn_Tioga_Pass_MB.brd

R8F34  RES  4.75K 1% CHIP  pkg 0402  page 162 : A = P3V3_STBY ; B = PU_SPI_BMC_BT_WP_N

(kicad_pcb
	(version 20260206)
	(generator "pcbnew")
	(generator_version "10.0")
	(general
		(thickness 1.6)
		(legacy_teardrops no)
	)
	(paper "A4")
	(title_block
		(title "Wiwynn_Tioga_Pass_MB.brd")
		(comment 1 "Tioga Pass / footprints 2253-2253 of 4770")
	)
	(layers
		(0 "F.Cu" signal "TOP")
		(4 "In1.Cu" signal "L2GND")
		(6 "In2.Cu" signal "L3")
		(8 "In3.Cu" signal "L4GND")
		(10 "In4.Cu" signal "L5")
		(12 "In5.Cu" signal "L6GND")
		(14 "In6.Cu" signal "L7VCC")
		(16 "In7.Cu" signal "L8VCC")
		(18 "In8.Cu" signal "L9GND")
		(20 "In9.Cu" signal "L10")
		(22 "In10.Cu" signal "L11GND")
		(24 "In11.Cu" signal "L12")
		(26 "In12.Cu" signal "L13GND")
		(2 "B.Cu" signal "BOTTOM")
		(9 "F.Adhes" user "F.Adhesive")
		(11 "B.Adhes" user "B.Adhesive")
		(13 "F.Paste" user "Package Geometry/Pastemask Top")
		(15 "B.Paste" user "Package Geometry/Pastemask Bottom")
		(5 "F.SilkS" user "Ref Des/Silkscreen Top")
		(7 "B.SilkS" user "Ref Des/Silkscreen Bottom")
		(1 "F.Mask" user "Board Geometry/Soldermask Top")
		(3 "B.Mask" user "Board Geometry/Soldermask Bottom")
		(17 "Dwgs.User" user "User.Drawings")
		(19 "Cmts.User" user "User.Comments")
		(21 "Eco1.User" user "User.Eco1")
		(23 "Eco2.User" user "User.Eco2")
		(25 "Edge.Cuts" user "Board Geometry/Outline")
		(27 "Margin" user)
		(31 "F.CrtYd" user "Package Geometry/Place Bound Top")
		(29 "B.CrtYd" user "Package Geometry/Place Bound Bottom")
		(35 "F.Fab" user "Ref Des/Assembly Top")
		(33 "B.Fab" user "Ref Des/Assembly Bottom")
	)
	(footprint ""
		(layer "F.Cu")
		(at 380.74219 -37.22751)
		(property "Reference" "R8F34"
			(at 0 0 0)
			(layer "F.SilkS")
			(hide yes)
			(effects
				(font
					(size 1.27 1.27)
				)
			)
		)
		(property "Value" ""
			(at 0 0 0)
			(layer "F.Fab")
			(effects
				(font
					(size 1.27 1.27)
				)
			)
		)
		(duplicate_pad_numbers_are_jumpers no)
		(fp_poly
			(pts
				(xy -0.2794 -0.1016) (xy 0.2794 -0.1016) (xy 0.2794 0.9906) (xy -0.2794 0.9906)
			)
			(stroke
				(width 0)
				(type default)
			)
			(fill no)
			(layer "F.CrtYd")
		)
		(fp_line
			(start -0.2794 -0.1016)
			(end -0.2794 0.9906)
			(stroke
				(width 0.1)
				(type default)
			)
			(layer "F.Fab")
		)
		(fp_line
			(start -0.2794 0.9906)
			(end 0.2794 0.9906)
			(stroke
				(width 0.1)
				(type default)
			)
			(layer "F.Fab")
		)
		(fp_line
			(start 0.2794 -0.1016)
			(end -0.2794 -0.1016)
			(stroke
				(width 0.1)
				(type default)
			)
			(layer "F.Fab")
		)
		(fp_line
			(start 0.2794 0.9906)
			(end 0.2794 -0.1016)
			(stroke
				(width 0.1)
				(type default)
			)
			(layer "F.Fab")
		)
		(pad "1" smd rect
			(at 0 0)
			(size 0.508 0.508)
			(layers "F.Cu" "F.Mask" "F.Paste")
			(net "P3V3_STBY")
		)
		(pad "2" smd rect
			(at 0 0.889)
			(size 0.508 0.508)
			(layers "F.Cu" "F.Mask" "F.Paste")
			(net "PU_SPI_BMC_BT_WP_N")
		)
		(zone
			(layer "F.Cu")
			(hatch none 0.5)
			(connect_pads
				(clearance 0)
			)
			(min_thickness 0.25)
			(keepout
				(tracks allowed)
				(vias not_allowed)
				(pads allowed)
				(copperpour not_allowed)
				(footprints allowed)
			)
			(placement
				(enabled no)
				(sheetname "")
			)
			(fill
				(thermal_gap 0.5)
				(thermal_bridge_width 0.5)
				(island_removal_mode 0)
			)
			(polygon
				(pts
					(xy 380.48819 -36.97351) (xy 380.99619 -36.97351) (xy 380.99619 -36.59251) (xy 380.48819 -36.59251)
				)
			)
		)
		(zone
			(layer "F.Cu")
			(hatch none 0.5)
			(connect_pads
				(clearance 0)
			)
			(min_thickness 0.25)
			(keepout
				(tracks not_allowed)
				(vias allowed)
				(pads allowed)
				(copperpour not_allowed)
				(footprints allowed)
			)
			(placement
				(enabled no)
				(sheetname "")
			)
			(fill
				(thermal_gap 0.5)
				(thermal_bridge_width 0.5)
				(island_removal_mode 0)
			)
			(polygon
				(pts
					(xy 380.48819 -36.59251) (xy 380.99619 -36.59251) (xy 380.99619 -36.97351) (xy 380.48819 -36.97351)
				)
			)
		)
	)
)
